(kicad_pcb
	(version 20260206)
	(generator "pcbnew")
	(generator_version "10.0")
	(general
		(thickness 1.6)
		(legacy_teardrops no)
	)
	(paper "A4")
	(title_block
		(title "04192023_DAF0TMB3IC0_F0TG_MB_C_brd_V02_OCP.brd")
		(comment 1 "Grand Teton / footprint 4934 of 8354 (J102), pads 227-291 of 291")
	)
	(layers
		(0 "F.Cu" signal "TOP")
		(4 "In1.Cu" signal "GND")
		(6 "In2.Cu" signal "IN1")
		(8 "In3.Cu" signal "GND1")
		(10 "In4.Cu" signal "IN2")
		(12 "In5.Cu" signal "GND2")
		(14 "In6.Cu" signal "IN3")
		(16 "In7.Cu" signal "GND3")
		(18 "In8.Cu" signal "VCC")
		(20 "In9.Cu" signal "VCC1")
		(22 "In10.Cu" signal "GND4")
		(24 "In11.Cu" signal "IN4")
		(26 "In12.Cu" signal "GND5")
		(28 "In13.Cu" signal "IN5")
		(30 "In14.Cu" signal "GND6")
		(32 "In15.Cu" signal "IN6")
		(34 "In16.Cu" signal "GND7")
		(2 "B.Cu" signal "BOTTOM")
		(9 "F.Adhes" user "F.Adhesive")
		(11 "B.Adhes" user "B.Adhesive")
		(13 "F.Paste" user "Package Geometry/Pastemask Top")
		(15 "B.Paste" user "Package Geometry/Pastemask Bottom")
		(5 "F.SilkS" user "Ref Des/Silkscreen Top")
		(7 "B.SilkS" user "Ref Des/Silkscreen Bottom")
		(1 "F.Mask" user "Board Geometry/Soldermask Top")
		(3 "B.Mask" user "Board Geometry/Soldermask Bottom")
		(17 "Dwgs.User" user "User.Drawings")
		(19 "Cmts.User" user "User.Comments")
		(21 "Eco1.User" user "User.Eco1")
		(23 "Eco2.User" user "User.Eco2")
		(25 "Edge.Cuts" user "Board Geometry/Outline")
		(27 "Margin" user)
		(31 "F.CrtYd" user "Package Geometry/Place Bound Top")
		(29 "B.CrtYd" user "Package Geometry/Place Bound Bottom")
		(35 "F.Fab" user "Ref Des/Assembly Top")
		(33 "B.Fab" user "Ref Des/Assembly Bottom")
	)
	(footprint ""
		(layer "F.Cu")
		(at 166.47795 -255.560322 180)
		(property "Reference" "J102"
			(at -2.7178 -81.857088 0)
			(unlocked yes)
			(layer "F.SilkS")
			(effects
				(font
					(size 0.7874 0.5842)
					(thickness 0.1524)
				)
			)
		)
		(property "Value" ""
			(at 0 0 180)
			(layer "F.Fab")
			(effects
				(font
					(size 1.27 1.27)
				)
			)
		)
		(duplicate_pad_numbers_are_jumpers no)
		(pad "227" smd rect
			(at 2.050034 11.474958 90)
			(size 0.519938 1.4986)
			(layers "F.Cu" "F.Mask" "F.Paste")
			(net "M_G_CPU1_SB_PAR")
		)
		(pad "228" smd rect
			(at 2.050034 12.325096 90)
			(size 0.519938 1.4986)
			(layers "F.Cu" "F.Mask" "F.Paste")
			(net "GND")
		)
		(pad "229" smd rect
			(at 2.050034 13.17498 90)
			(size 0.519938 1.4986)
			(layers "F.Cu" "F.Mask" "F.Paste")
			(net "M_G_CPU1_SB_CS_N<1>")
		)
		(pad "230" smd rect
			(at 2.050034 14.025118 90)
			(size 0.519938 1.4986)
			(layers "F.Cu" "F.Mask" "F.Paste")
			(net "GND")
		)
		(pad "231" smd rect
			(at 2.050034 14.875002 90)
			(size 0.519938 1.4986)
			(layers "F.Cu" "F.Mask" "F.Paste")
			(net "Net_2345")
		)
		(pad "232" smd rect
			(at 2.050034 15.724886 90)
			(size 0.519938 1.4986)
			(layers "F.Cu" "F.Mask" "F.Paste")
			(net "Net_2346")
		)
		(pad "233" smd rect
			(at 2.050034 16.575024 90)
			(size 0.519938 1.4986)
			(layers "F.Cu" "F.Mask" "F.Paste")
			(net "GND")
		)
		(pad "234" smd rect
			(at 2.050034 17.424908 90)
			(size 0.519938 1.4986)
			(layers "F.Cu" "F.Mask" "F.Paste")
			(net "M_G_CPU1_SB_CB<6>")
		)
		(pad "235" smd rect
			(at 2.050034 18.275046 90)
			(size 0.519938 1.4986)
			(layers "F.Cu" "F.Mask" "F.Paste")
			(net "GND")
		)
		(pad "236" smd rect
			(at 2.050034 19.12493 90)
			(size 0.519938 1.4986)
			(layers "F.Cu" "F.Mask" "F.Paste")
			(net "M_G_CPU1_SB_CB<7>")
		)
		(pad "237" smd rect
			(at 2.050034 19.975068 90)
			(size 0.519938 1.4986)
			(layers "F.Cu" "F.Mask" "F.Paste")
			(net "GND")
		)
		(pad "238" smd rect
			(at 2.050034 20.824952 90)
			(size 0.519938 1.4986)
			(layers "F.Cu" "F.Mask" "F.Paste")
			(net "M_G_CPU1_SB_DQS_DN<4>")
		)
		(pad "239" smd rect
			(at 2.050034 21.67509 90)
			(size 0.519938 1.4986)
			(layers "F.Cu" "F.Mask" "F.Paste")
			(net "M_G_CPU1_SB_DQS_DP<4>")
		)
		(pad "240" smd rect
			(at 2.050034 22.524974 90)
			(size 0.519938 1.4986)
			(layers "F.Cu" "F.Mask" "F.Paste")
			(net "GND")
		)
		(pad "241" smd rect
			(at 2.050034 23.375112 90)
			(size 0.519938 1.4986)
			(layers "F.Cu" "F.Mask" "F.Paste")
			(net "M_G_CPU1_SB_CB<2>")
		)
		(pad "242" smd rect
			(at 2.050034 24.224996 90)
			(size 0.519938 1.4986)
			(layers "F.Cu" "F.Mask" "F.Paste")
			(net "GND")
		)
		(pad "243" smd rect
			(at 2.050034 25.07488 90)
			(size 0.519938 1.4986)
			(layers "F.Cu" "F.Mask" "F.Paste")
			(net "M_G_CPU1_SB_CB<3>")
		)
		(pad "244" smd rect
			(at 2.050034 25.925018 90)
			(size 0.519938 1.4986)
			(layers "F.Cu" "F.Mask" "F.Paste")
			(net "GND")
		)
		(pad "245" smd rect
			(at 2.050034 26.774902 90)
			(size 0.519938 1.4986)
			(layers "F.Cu" "F.Mask" "F.Paste")
			(net "M_G_CPU1_SB_DQ<2>")
		)
		(pad "246" smd rect
			(at 2.050034 27.62504 90)
			(size 0.519938 1.4986)
			(layers "F.Cu" "F.Mask" "F.Paste")
			(net "GND")
		)
		(pad "247" smd rect
			(at 2.050034 28.474924 90)
			(size 0.519938 1.4986)
			(layers "F.Cu" "F.Mask" "F.Paste")
			(net "M_G_CPU1_SB_DQ<3>")
		)
		(pad "248" smd rect
			(at 2.050034 29.325062 90)
			(size 0.519938 1.4986)
			(layers "F.Cu" "F.Mask" "F.Paste")
			(net "GND")
		)
		(pad "249" smd rect
			(at 2.050034 30.174946 90)
			(size 0.519938 1.4986)
			(layers "F.Cu" "F.Mask" "F.Paste")
			(net "M_G_CPU1_SB_DQS_DN<5>")
		)
		(pad "250" smd rect
			(at 2.050034 31.025084 90)
			(size 0.519938 1.4986)
			(layers "F.Cu" "F.Mask" "F.Paste")
			(net "M_G_CPU1_SB_DQS_DP<5>")
		)
		(pad "251" smd rect
			(at 2.050034 31.874968 90)
			(size 0.519938 1.4986)
			(layers "F.Cu" "F.Mask" "F.Paste")
			(net "GND")
		)
		(pad "252" smd rect
			(at 2.050034 32.725106 90)
			(size 0.519938 1.4986)
			(layers "F.Cu" "F.Mask" "F.Paste")
			(net "M_G_CPU1_SB_DQ<6>")
		)
		(pad "253" smd rect
			(at 2.050034 33.57499 90)
			(size 0.519938 1.4986)
			(layers "F.Cu" "F.Mask" "F.Paste")
			(net "GND")
		)
		(pad "254" smd rect
			(at 2.050034 34.425128 90)
			(size 0.519938 1.4986)
			(layers "F.Cu" "F.Mask" "F.Paste")
			(net "M_G_CPU1_SB_DQ<7>")
		)
		(pad "255" smd rect
			(at 2.050034 35.275012 90)
			(size 0.519938 1.4986)
			(layers "F.Cu" "F.Mask" "F.Paste")
			(net "GND")
		)
		(pad "256" smd rect
			(at 2.050034 36.124896 90)
			(size 0.519938 1.4986)
			(layers "F.Cu" "F.Mask" "F.Paste")
			(net "M_G_CPU1_SB_DQ<10>")
		)
		(pad "257" smd rect
			(at 2.050034 36.975034 90)
			(size 0.519938 1.4986)
			(layers "F.Cu" "F.Mask" "F.Paste")
			(net "GND")
		)
		(pad "258" smd rect
			(at 2.050034 37.824918 90)
			(size 0.519938 1.4986)
			(layers "F.Cu" "F.Mask" "F.Paste")
			(net "M_G_CPU1_SB_DQ<11>")
		)
		(pad "259" smd rect
			(at 2.050034 38.675056 90)
			(size 0.519938 1.4986)
			(layers "F.Cu" "F.Mask" "F.Paste")
			(net "GND")
		)
		(pad "260" smd rect
			(at 2.050034 39.52494 90)
			(size 0.519938 1.4986)
			(layers "F.Cu" "F.Mask" "F.Paste")
			(net "M_G_CPU1_SB_DQS_DN<6>")
		)
		(pad "261" smd rect
			(at 2.050034 40.375078 90)
			(size 0.519938 1.4986)
			(layers "F.Cu" "F.Mask" "F.Paste")
			(net "M_G_CPU1_SB_DQS_DP<6>")
		)
		(pad "262" smd rect
			(at 2.050034 41.224962 90)
			(size 0.519938 1.4986)
			(layers "F.Cu" "F.Mask" "F.Paste")
			(net "GND")
		)
		(pad "263" smd rect
			(at 2.050034 42.0751 90)
			(size 0.519938 1.4986)
			(layers "F.Cu" "F.Mask" "F.Paste")
			(net "M_G_CPU1_SB_DQ<14>")
		)
		(pad "264" smd rect
			(at 2.050034 42.924984 90)
			(size 0.519938 1.4986)
			(layers "F.Cu" "F.Mask" "F.Paste")
			(net "GND")
		)
		(pad "265" smd rect
			(at 2.050034 43.775122 90)
			(size 0.519938 1.4986)
			(layers "F.Cu" "F.Mask" "F.Paste")
			(net "M_G_CPU1_SB_DQ<15>")
		)
		(pad "266" smd rect
			(at 2.050034 44.625006 90)
			(size 0.519938 1.4986)
			(layers "F.Cu" "F.Mask" "F.Paste")
			(net "GND")
		)
		(pad "267" smd rect
			(at 2.050034 45.47489 90)
			(size 0.519938 1.4986)
			(layers "F.Cu" "F.Mask" "F.Paste")
			(net "M_G_CPU1_SB_DQ<18>")
		)
		(pad "268" smd rect
			(at 2.050034 46.325028 90)
			(size 0.519938 1.4986)
			(layers "F.Cu" "F.Mask" "F.Paste")
			(net "GND")
		)
		(pad "269" smd rect
			(at 2.050034 47.174912 90)
			(size 0.519938 1.4986)
			(layers "F.Cu" "F.Mask" "F.Paste")
			(net "M_G_CPU1_SB_DQ<19>")
		)
		(pad "270" smd rect
			(at 2.050034 48.02505 90)
			(size 0.519938 1.4986)
			(layers "F.Cu" "F.Mask" "F.Paste")
			(net "GND")
		)
		(pad "271" smd rect
			(at 2.050034 48.874934 90)
			(size 0.519938 1.4986)
			(layers "F.Cu" "F.Mask" "F.Paste")
			(net "M_G_CPU1_SB_DQS_DN<7>")
		)
		(pad "272" smd rect
			(at 2.050034 49.725072 90)
			(size 0.519938 1.4986)
			(layers "F.Cu" "F.Mask" "F.Paste")
			(net "M_G_CPU1_SB_DQS_DP<7>")
		)
		(pad "273" smd rect
			(at 2.050034 50.574956 90)
			(size 0.519938 1.4986)
			(layers "F.Cu" "F.Mask" "F.Paste")
			(net "GND")
		)
		(pad "274" smd rect
			(at 2.050034 51.425094 90)
			(size 0.519938 1.4986)
			(layers "F.Cu" "F.Mask" "F.Paste")
			(net "M_G_CPU1_SB_DQ<22>")
		)
		(pad "275" smd rect
			(at 2.050034 52.274978 90)
			(size 0.519938 1.4986)
			(layers "F.Cu" "F.Mask" "F.Paste")
			(net "GND")
		)
		(pad "276" smd rect
			(at 2.050034 53.125116 90)
			(size 0.519938 1.4986)
			(layers "F.Cu" "F.Mask" "F.Paste")
			(net "M_G_CPU1_SB_DQ<23>")
		)
		(pad "277" smd rect
			(at 2.050034 53.975 90)
			(size 0.519938 1.4986)
			(layers "F.Cu" "F.Mask" "F.Paste")
			(net "GND")
		)
		(pad "278" smd rect
			(at 2.050034 54.824884 90)
			(size 0.519938 1.4986)
			(layers "F.Cu" "F.Mask" "F.Paste")
			(net "M_G_CPU1_SB_DQ<26>")
		)
		(pad "279" smd rect
			(at 2.050034 55.675022 90)
			(size 0.519938 1.4986)
			(layers "F.Cu" "F.Mask" "F.Paste")
			(net "GND")
		)
		(pad "280" smd rect
			(at 2.050034 56.524906 90)
			(size 0.519938 1.4986)
			(layers "F.Cu" "F.Mask" "F.Paste")
			(net "M_G_CPU1_SB_DQ<27>")
		)
		(pad "281" smd rect
			(at 2.050034 57.375044 90)
			(size 0.519938 1.4986)
			(layers "F.Cu" "F.Mask" "F.Paste")
			(net "GND")
		)
		(pad "282" smd rect
			(at 2.050034 58.224928 90)
			(size 0.519938 1.4986)
			(layers "F.Cu" "F.Mask" "F.Paste")
			(net "M_G_CPU1_SB_DQS_DN<8>")
		)
		(pad "283" smd rect
			(at 2.050034 59.075066 90)
			(size 0.519938 1.4986)
			(layers "F.Cu" "F.Mask" "F.Paste")
			(net "M_G_CPU1_SB_DQS_DP<8>")
		)
		(pad "284" smd rect
			(at 2.050034 59.92495 90)
			(size 0.519938 1.4986)
			(layers "F.Cu" "F.Mask" "F.Paste")
			(net "GND")
		)
		(pad "285" smd rect
			(at 2.050034 60.775088 90)
			(size 0.519938 1.4986)
			(layers "F.Cu" "F.Mask" "F.Paste")
			(net "M_G_CPU1_SB_DQ<30>")
		)
		(pad "286" smd rect
			(at 2.050034 61.624972 90)
			(size 0.519938 1.4986)
			(layers "F.Cu" "F.Mask" "F.Paste")
			(net "GND")
		)
		(pad "287" smd rect
			(at 2.050034 62.47511 90)
			(size 0.519938 1.4986)
			(layers "F.Cu" "F.Mask" "F.Paste")
			(net "M_G_CPU1_SB_DQ<31>")
		)
		(pad "288" smd rect
			(at 2.050034 63.324994 90)
			(size 0.519938 1.4986)
			(layers "F.Cu" "F.Mask" "F.Paste")
			(net "GND")
		)
		(pad "G1" thru_hole oval
			(at 0 -68.97497 90)
			(size 1.7272 3.4798)
			(drill oval 1.2192 2.4638)
			(layers "*.Cu" "*.Mask")
			(remove_unused_layers no)
			(net "GND")
			(clearance 0.127)
			(thermal_gap 0.127)
		)
		(pad "G2" thru_hole oval
			(at 0 3.875024 90)
			(size 1.7272 3.4798)
			(drill oval 1.2192 2.4638)
			(layers "*.Cu" "*.Mask")
			(remove_unused_layers no)
			(net "GND")
			(clearance 0.127)
			(thermal_gap 0.127)
		)
		(pad "G3" thru_hole oval
			(at 0 68.97497 90)
			(size 1.7272 3.4798)
			(drill oval 1.2192 2.4638)
			(layers "*.Cu" "*.Mask")
			(remove_unused_layers no)
			(net "GND")
			(clearance 0.127)
			(thermal_gap 0.127)
		)
	)
)
